# S9S_MB_2U (Grand Teton) — schematic netlist excerpt (pin names and nets, part order shuffled) for the footprints in the layout excerpt that follows; sources: Cadence DE-HDL packaged netlist, KiCad conversion of 03242023_DA0F0TMBIJ0_F0T_Motherboard_J_brd_V01_OCP.brd

C417  Q_CAP  22UF 4V 20% X6S  pkg C0402  page 74 : A = PVCCFA_EHV_FIVRA_CPU0 ; B = GND
PC296_P0_2  Q_CAP  3300PF 50V 10% X7R  pkg 0402  page 267 : A = SW_P12V_PVCCIN_CPU0_FLT ; B = GND

(kicad_pcb
	(version 20260206)
	(generator "pcbnew")
	(generator_version "10.0")
	(general
		(thickness 1.6)
		(legacy_teardrops no)
	)
	(paper "A4")
	(title_block
		(title "03242023_DA0F0TMBIJ0_F0T_Motherboard_J_brd_V01_OCP.brd")
		(comment 1 "Grand Teton / footprints 1311-1312 of 6105")
	)
	(layers
		(0 "F.Cu" signal "TOP")
		(4 "In1.Cu" signal "GND")
		(6 "In2.Cu" signal "IN1")
		(8 "In3.Cu" signal "GND1")
		(10 "In4.Cu" signal "IN2")
		(12 "In5.Cu" signal "GND2")
		(14 "In6.Cu" signal "IN3")
		(16 "In7.Cu" signal "GND3")
		(18 "In8.Cu" signal "VCC")
		(20 "In9.Cu" signal "VCC1")
		(22 "In10.Cu" signal "GND4")
		(24 "In11.Cu" signal "IN4")
		(26 "In12.Cu" signal "GND5")
		(28 "In13.Cu" signal "IN5")
		(30 "In14.Cu" signal "GND6")
		(32 "In15.Cu" signal "IN6")
		(34 "In16.Cu" signal "GND7")
		(2 "B.Cu" signal "BOTTOM")
		(9 "F.Adhes" user "F.Adhesive")
		(11 "B.Adhes" user "B.Adhesive")
		(13 "F.Paste" user "Package Geometry/Pastemask Top")
		(15 "B.Paste" user "Package Geometry/Pastemask Bottom")
		(5 "F.SilkS" user "Ref Des/Silkscreen Top")
		(7 "B.SilkS" user "Ref Des/Silkscreen Bottom")
		(1 "F.Mask" user "Board Geometry/Soldermask Top")
		(3 "B.Mask" user "Board Geometry/Soldermask Bottom")
		(17 "Dwgs.User" user "User.Drawings")
		(19 "Cmts.User" user "User.Comments")
		(21 "Eco1.User" user "User.Eco1")
		(23 "Eco2.User" user "User.Eco2")
		(25 "Edge.Cuts" user "Board Geometry/Outline")
		(27 "Margin" user)
		(31 "F.CrtYd" user "Package Geometry/Place Bound Top")
		(29 "B.CrtYd" user "Package Geometry/Place Bound Bottom")
		(35 "F.Fab" user "Ref Des/Assembly Top")
		(33 "B.Fab" user "Ref Des/Assembly Bottom")
	)
	(footprint ""
		(layer "F.Cu")
		(at 356.945184 -337.830668)
		(property "Reference" "PC296_P0_2"
			(at 0 0 0)
			(layer "F.SilkS")
			(hide yes)
			(effects
				(font
					(size 1.27 1.27)
				)
			)
		)
		(property "Value" ""
			(at 0 0 0)
			(layer "F.Fab")
			(effects
				(font
					(size 1.27 1.27)
				)
			)
		)
		(duplicate_pad_numbers_are_jumpers no)
		(fp_line
			(start -0.7874 -0.4064)
			(end 0.7874 -0.4064)
			(stroke
				(width 0.1524)
				(type default)
			)
			(layer "F.SilkS")
		)
		(fp_line
			(start -0.7874 0.4064)
			(end -0.7874 -0.4064)
			(stroke
				(width 0.1524)
				(type default)
			)
			(layer "F.SilkS")
		)
		(fp_line
			(start 0.7874 -0.4064)
			(end 0.7874 0.4064)
			(stroke
				(width 0.1524)
				(type default)
			)
			(layer "F.SilkS")
		)
		(fp_line
			(start 0.7874 0.4064)
			(end -0.7874 0.4064)
			(stroke
				(width 0.1524)
				(type default)
			)
			(layer "F.SilkS")
		)
		(fp_line
			(start -0.67945 -0.305054)
			(end -0.12065 -0.305054)
			(stroke
				(width 0.1)
				(type default)
			)
			(layer "F.Fab")
		)
		(fp_line
			(start -0.67945 0.3048)
			(end -0.67945 -0.305054)
			(stroke
				(width 0.1)
				(type default)
			)
			(layer "F.Fab")
		)
		(fp_line
			(start -0.12065 -0.305054)
			(end -0.12065 -0.2794)
			(stroke
				(width 0.1)
				(type default)
			)
			(layer "F.Fab")
		)
		(fp_line
			(start -0.12065 -0.2794)
			(end 0.12065 -0.2794)
			(stroke
				(width 0.1)
				(type default)
			)
			(layer "F.Fab")
		)
		(fp_line
			(start -0.12065 0.2794)
			(end -0.12065 0.3048)
			(stroke
				(width 0.1)
				(type default)
			)
			(layer "F.Fab")
		)
		(fp_line
			(start -0.12065 0.3048)
			(end -0.67945 0.3048)
			(stroke
				(width 0.1)
				(type default)
			)
			(layer "F.Fab")
		)
		(fp_line
			(start 0.120396 0.2794)
			(end -0.12065 0.2794)
			(stroke
				(width 0.1)
				(type default)
			)
			(layer "F.Fab")
		)
		(fp_line
			(start 0.120396 0.3048)
			(end 0.120396 0.2794)
			(stroke
				(width 0.1)
				(type default)
			)
			(layer "F.Fab")
		)
		(fp_line
			(start 0.12065 -0.3048)
			(end 0.67945 -0.3048)
			(stroke
				(width 0.1)
				(type default)
			)
			(layer "F.Fab")
		)
		(fp_line
			(start 0.12065 -0.2794)
			(end 0.12065 -0.3048)
			(stroke
				(width 0.1)
				(type default)
			)
			(layer "F.Fab")
		)
		(fp_line
			(start 0.67945 -0.3048)
			(end 0.67945 0.3048)
			(stroke
				(width 0.1)
				(type default)
			)
			(layer "F.Fab")
		)
		(fp_line
			(start 0.67945 0.3048)
			(end 0.120396 0.3048)
			(stroke
				(width 0.1)
				(type default)
			)
			(layer "F.Fab")
		)
		(pad "1" smd circle
			(at -0.40005 0)
			(size 0 0)
			(layers "F.Cu" "F.Mask" "F.Paste")
			(net "SW_P12V_PVCCIN_CPU0_FLT")
		)
		(pad "2" smd circle
			(at 0.40005 0)
			(size 0 0)
			(layers "F.Cu" "F.Mask" "F.Paste")
			(net "GND")
		)
	)
	(footprint ""
		(layer "F.Cu")
		(at 352.287078 -238.162338 -90)
		(property "Reference" "C417"
			(at 0 0 270)
			(layer "F.SilkS")
			(hide yes)
			(effects
				(font
					(size 1.27 1.27)
				)
			)
		)
		(property "Value" ""
			(at 0 0 270)
			(layer "F.Fab")
			(effects
				(font
					(size 1.27 1.27)
				)
			)
		)
		(duplicate_pad_numbers_are_jumpers no)
		(fp_line
			(start -0.7874 0.4064)
			(end -0.7874 -0.4064)
			(stroke
				(width 0.1524)
				(type default)
			)
			(layer "F.SilkS")
		)
		(fp_line
			(start 0.7874 0.4064)
			(end -0.7874 0.4064)
			(stroke
				(width 0.1524)
				(type default)
			)
			(layer "F.SilkS")
		)
		(fp_line
			(start -0.7874 -0.4064)
			(end 0.7874 -0.4064)
			(stroke
				(width 0.1524)
				(type default)
			)
			(layer "F.SilkS")
		)
		(fp_line
			(start 0.7874 -0.4064)
			(end 0.7874 0.4064)
			(stroke
				(width 0.1524)
				(type default)
			)
			(layer "F.SilkS")
		)
		(fp_line
			(start -0.67945 0.3048)
			(end -0.67945 -0.305054)
			(stroke
				(width 0.1)
				(type default)
			)
			(layer "F.Fab")
		)
		(fp_line
			(start -0.12065 0.3048)
			(end -0.67945 0.3048)
			(stroke
				(width 0.1)
				(type default)
			)
			(layer "F.Fab")
		)
		(fp_line
			(start 0.120396 0.3048)
			(end 0.120396 0.2794)
			(stroke
				(width 0.1)
				(type default)
			)
			(layer "F.Fab")
		)
		(fp_line
			(start 0.67945 0.3048)
			(end 0.120396 0.3048)
			(stroke
				(width 0.1)
				(type default)
			)
			(layer "F.Fab")
		)
		(fp_line
			(start -0.12065 0.2794)
			(end -0.12065 0.3048)
			(stroke
				(width 0.1)
				(type default)
			)
			(layer "F.Fab")
		)
		(fp_line
			(start 0.120396 0.2794)
			(end -0.12065 0.2794)
			(stroke
				(width 0.1)
				(type default)
			)
			(layer "F.Fab")
		)
		(fp_line
			(start -0.12065 -0.2794)
			(end 0.12065 -0.2794)
			(stroke
				(width 0.1)
				(type default)
			)
			(layer "F.Fab")
		)
		(fp_line
			(start 0.12065 -0.2794)
			(end 0.12065 -0.3048)
			(stroke
				(width 0.1)
				(type default)
			)
			(layer "F.Fab")
		)
		(fp_line
			(start 0.12065 -0.3048)
			(end 0.67945 -0.3048)
			(stroke
				(width 0.1)
				(type default)
			)
			(layer "F.Fab")
		)
		(fp_line
			(start 0.67945 -0.3048)
			(end 0.67945 0.3048)
			(stroke
				(width 0.1)
				(type default)
			)
			(layer "F.Fab")
		)
		(fp_line
			(start -0.67945 -0.305054)
			(end -0.12065 -0.305054)
			(stroke
				(width 0.1)
				(type default)
			)
			(layer "F.Fab")
		)
		(fp_line
			(start -0.12065 -0.305054)
			(end -0.12065 -0.2794)
			(stroke
				(width 0.1)
				(type default)
			)
			(layer "F.Fab")
		)
		(pad "1" smd circle
			(at -0.40005 0 270)
			(size 0 0)
			(layers "F.Cu" "F.Mask" "F.Paste")
			(net "PVCCFA_EHV_FIVRA_CPU0")
		)
		(pad "2" smd circle
			(at 0.40005 0 270)
			(size 0 0)
			(layers "F.Cu" "F.Mask" "F.Paste")
			(net "GND")
		)
	)
)
